(kicad_pcb
	(version 20260206)
	(generator "pcbnew")
	(generator_version "10.0")
	(general
		(thickness 1.6)
		(legacy_teardrops no)
	)
	(paper "A4")
	(title_block
		(title "01162023_DA0F0TEBIF0_F0T_Expander_BD_F_brd_V02_OCP.brd")
		(comment 1 "Grand Teton / footprint 4451 of 9728 (PEX3), pads 2359-2397 of 2397")
	)
	(layers
		(0 "F.Cu" signal "TOP")
		(4 "In1.Cu" signal "GND")
		(6 "In2.Cu" signal "VCC")
		(8 "In3.Cu" signal "VCC1")
		(10 "In4.Cu" signal "GND1")
		(12 "In5.Cu" signal "IN1")
		(14 "In6.Cu" signal "GND2")
		(16 "In7.Cu" signal "IN2")
		(18 "In8.Cu" signal "GND3")
		(20 "In9.Cu" signal "IN3")
		(22 "In10.Cu" signal "GND4")
		(24 "In11.Cu" signal "IN4")
		(26 "In12.Cu" signal "GND5")
		(28 "In13.Cu" signal "IN5")
		(30 "In14.Cu" signal "GND6")
		(32 "In15.Cu" signal "IN6")
		(34 "In16.Cu" signal "GND7")
		(2 "B.Cu" signal "BOTTOM")
		(9 "F.Adhes" user "F.Adhesive")
		(11 "B.Adhes" user "B.Adhesive")
		(13 "F.Paste" user "Package Geometry/Pastemask Top")
		(15 "B.Paste" user "Package Geometry/Pastemask Bottom")
		(5 "F.SilkS" user "Ref Des/Silkscreen Top")
		(7 "B.SilkS" user "Ref Des/Silkscreen Bottom")
		(1 "F.Mask" user "Board Geometry/Soldermask Top")
		(3 "B.Mask" user "Board Geometry/Soldermask Bottom")
		(17 "Dwgs.User" user "User.Drawings")
		(19 "Cmts.User" user "User.Comments")
		(21 "Eco1.User" user "User.Eco1")
		(23 "Eco2.User" user "User.Eco2")
		(25 "Edge.Cuts" user "Board Geometry/Outline")
		(27 "Margin" user)
		(31 "F.CrtYd" user "Package Geometry/Place Bound Top")
		(29 "B.CrtYd" user "Package Geometry/Place Bound Bottom")
		(35 "F.Fab" user "Ref Des/Assembly Top")
		(33 "B.Fab" user "Ref Des/Assembly Bottom")
	)
	(footprint ""
		(layer "F.Cu")
		(at 407.949908 -295.89984)
		(property "Reference" "PEX3"
			(at -3.358642 35.5727 0)
			(unlocked yes)
			(layer "F.SilkS")
			(effects
				(font
					(size 2.032 1.524)
					(thickness 0.1524)
				)
				(justify left)
			)
		)
		(property "Value" ""
			(at 0 0 0)
			(layer "F.Fab")
			(effects
				(font
					(size 1.27 1.27)
				)
			)
		)
		(duplicate_pad_numbers_are_jumpers no)
		(pad "Y11" smd circle
			(at -13.299948 -4.750054)
			(size 0.4572 0.4572)
			(layers "F.Cu" "F.Mask" "F.Paste")
			(net "GND")
		)
		(pad "Y12" smd circle
			(at -12.349988 -4.750054)
			(size 0.4572 0.4572)
			(layers "F.Cu" "F.Mask" "F.Paste")
			(net "P1V8_PEX")
		)
		(pad "Y13" smd circle
			(at -11.400028 -4.750054)
			(size 0.4572 0.4572)
			(layers "F.Cu" "F.Mask" "F.Paste")
			(net "GND")
		)
		(pad "Y14" smd circle
			(at -10.450068 -4.750054)
			(size 0.4572 0.4572)
			(layers "F.Cu" "F.Mask" "F.Paste")
			(net "P0V8_PEX3")
		)
		(pad "Y15" smd circle
			(at -9.500108 -4.750054)
			(size 0.4572 0.4572)
			(layers "F.Cu" "F.Mask" "F.Paste")
			(net "GND")
		)
		(pad "Y16" smd circle
			(at -8.549894 -4.750054)
			(size 0.4572 0.4572)
			(layers "F.Cu" "F.Mask" "F.Paste")
			(net "P0V8_SERDES_VDDA_PEX3")
		)
		(pad "Y17" smd circle
			(at -7.599934 -4.750054)
			(size 0.4572 0.4572)
			(layers "F.Cu" "F.Mask" "F.Paste")
			(net "P0V8_SERDES_VDDA_PEX3")
		)
		(pad "Y18" smd circle
			(at -6.649974 -4.750054)
			(size 0.4572 0.4572)
			(layers "F.Cu" "F.Mask" "F.Paste")
			(net "P0V8_SERDES_VDDA_PEX3")
		)
		(pad "Y19" smd circle
			(at -5.700014 -4.750054)
			(size 0.4572 0.4572)
			(layers "F.Cu" "F.Mask" "F.Paste")
			(net "P0V8_SERDES_VDDA_PEX3")
		)
		(pad "Y20" smd circle
			(at -4.750054 -4.750054)
			(size 0.4572 0.4572)
			(layers "F.Cu" "F.Mask" "F.Paste")
			(net "P0V8_SERDES_VDDA_PEX3")
		)
		(pad "Y21" smd circle
			(at -3.800094 -4.750054)
			(size 0.4572 0.4572)
			(layers "F.Cu" "F.Mask" "F.Paste")
			(net "P0V8_SERDES_VDDA_PEX3")
		)
		(pad "Y22" smd circle
			(at -2.84988 -4.750054)
			(size 0.4572 0.4572)
			(layers "F.Cu" "F.Mask" "F.Paste")
			(net "P0V8_SERDES_VDDA_PEX3")
		)
		(pad "Y23" smd circle
			(at -1.89992 -4.750054)
			(size 0.4572 0.4572)
			(layers "F.Cu" "F.Mask" "F.Paste")
			(net "P0V8_SERDES_VDDA_PEX3")
		)
		(pad "Y24" smd circle
			(at -0.94996 -4.750054)
			(size 0.4572 0.4572)
			(layers "F.Cu" "F.Mask" "F.Paste")
			(net "P0V8_SERDES_VDDA_PEX3")
		)
		(pad "Y25" smd circle
			(at 0 -4.750054)
			(size 0.4572 0.4572)
			(layers "F.Cu" "F.Mask" "F.Paste")
			(net "P0V8_SERDES_VDDA_PEX3")
		)
		(pad "Y26" smd circle
			(at 0.94996 -4.750054)
			(size 0.4572 0.4572)
			(layers "F.Cu" "F.Mask" "F.Paste")
			(net "P0V8_SERDES_VDDA_PEX3")
		)
		(pad "Y27" smd circle
			(at 1.89992 -4.750054)
			(size 0.4572 0.4572)
			(layers "F.Cu" "F.Mask" "F.Paste")
			(net "P0V8_SERDES_VDDA_PEX3")
		)
		(pad "Y28" smd circle
			(at 2.84988 -4.750054)
			(size 0.4572 0.4572)
			(layers "F.Cu" "F.Mask" "F.Paste")
			(net "P0V8_SERDES_VDDA_PEX3")
		)
		(pad "Y29" smd circle
			(at 3.800094 -4.750054)
			(size 0.4572 0.4572)
			(layers "F.Cu" "F.Mask" "F.Paste")
			(net "P0V8_SERDES_VDDA_PEX3")
		)
		(pad "Y30" smd circle
			(at 4.750054 -4.750054)
			(size 0.4572 0.4572)
			(layers "F.Cu" "F.Mask" "F.Paste")
			(net "P0V8_SERDES_VDDA_PEX3")
		)
		(pad "Y31" smd circle
			(at 5.700014 -4.750054)
			(size 0.4572 0.4572)
			(layers "F.Cu" "F.Mask" "F.Paste")
			(net "P0V8_SERDES_VDDA_PEX3")
		)
		(pad "Y32" smd circle
			(at 6.649974 -4.750054)
			(size 0.4572 0.4572)
			(layers "F.Cu" "F.Mask" "F.Paste")
			(net "P0V8_SERDES_VDDA_PEX3")
		)
		(pad "Y33" smd circle
			(at 7.599934 -4.750054)
			(size 0.4572 0.4572)
			(layers "F.Cu" "F.Mask" "F.Paste")
			(net "P0V8_SERDES_VDDA_PEX3")
		)
		(pad "Y34" smd circle
			(at 8.549894 -4.750054)
			(size 0.4572 0.4572)
			(layers "F.Cu" "F.Mask" "F.Paste")
			(net "GND")
		)
		(pad "Y35" smd circle
			(at 9.500108 -4.750054)
			(size 0.4572 0.4572)
			(layers "F.Cu" "F.Mask" "F.Paste")
			(net "P1V8_PEX")
		)
		(pad "Y36" smd circle
			(at 10.450068 -4.750054)
			(size 0.4572 0.4572)
			(layers "F.Cu" "F.Mask" "F.Paste")
			(net "GND")
		)
		(pad "Y37" smd circle
			(at 11.400028 -4.750054)
			(size 0.4572 0.4572)
			(layers "F.Cu" "F.Mask" "F.Paste")
			(net "GND")
		)
		(pad "Y38" smd circle
			(at 12.349988 -4.750054)
			(size 0.4572 0.4572)
			(layers "F.Cu" "F.Mask" "F.Paste")
			(net "GND")
		)
		(pad "Y39" smd circle
			(at 13.299948 -4.750054)
			(size 0.4572 0.4572)
			(layers "F.Cu" "F.Mask" "F.Paste")
			(net "PEX3_ADCTEMP_VINP0")
		)
		(pad "Y40" smd circle
			(at 14.249908 -4.750054)
			(size 0.4572 0.4572)
			(layers "F.Cu" "F.Mask" "F.Paste")
			(net "GND")
		)
		(pad "Y41" smd circle
			(at 15.200122 -4.750054)
			(size 0.4572 0.4572)
			(layers "F.Cu" "F.Mask" "F.Paste")
			(net "Net_1523")
		)
		(pad "Y42" smd circle
			(at 16.150082 -4.750054)
			(size 0.4572 0.4572)
			(layers "F.Cu" "F.Mask" "F.Paste")
			(net "Net_1561")
		)
		(pad "Y43" smd circle
			(at 17.100042 -4.750054)
			(size 0.4572 0.4572)
			(layers "F.Cu" "F.Mask" "F.Paste")
			(net "GND")
		)
		(pad "Y44" smd circle
			(at 18.050002 -4.750054)
			(size 0.4572 0.4572)
			(layers "F.Cu" "F.Mask" "F.Paste")
			(net "GND")
		)
		(pad "Y45" smd circle
			(at 18.999962 -4.750054)
			(size 0.4572 0.4572)
			(layers "F.Cu" "F.Mask" "F.Paste")
			(net "GND")
		)
		(pad "Y46" smd circle
			(at 19.949922 -4.750054)
			(size 0.4572 0.4572)
			(layers "F.Cu" "F.Mask" "F.Paste")
			(net "GND")
		)
		(pad "Y47" smd circle
			(at 20.899882 -4.750054)
			(size 0.4572 0.4572)
			(layers "F.Cu" "F.Mask" "F.Paste")
			(net "GND")
		)
		(pad "Y48" smd circle
			(at 21.850096 -4.750054)
			(size 0.4572 0.4572)
			(layers "F.Cu" "F.Mask" "F.Paste")
			(net "Net_1409")
		)
		(pad "Y49" smd circle
			(at 22.800056 -4.750054)
			(size 0.4572 0.4572)
			(layers "F.Cu" "F.Mask" "F.Paste")
			(net "Net_1451")
		)
	)
)
